(kicad_pcb
	(version 20260206)
	(generator "pcbnew")
	(generator_version "10.0")
	(general
		(thickness 1.6)
		(legacy_teardrops no)
	)
	(paper "A4")
	(title_block
		(title "Wiwynn_Tioga_Pass_MB.brd")
		(comment 1 "Tioga Pass / footprints 4067-4073 of 4770")
	)
	(layers
		(0 "F.Cu" signal "TOP")
		(4 "In1.Cu" signal "L2GND")
		(6 "In2.Cu" signal "L3")
		(8 "In3.Cu" signal "L4GND")
		(10 "In4.Cu" signal "L5")
		(12 "In5.Cu" signal "L6GND")
		(14 "In6.Cu" signal "L7VCC")
		(16 "In7.Cu" signal "L8VCC")
		(18 "In8.Cu" signal "L9GND")
		(20 "In9.Cu" signal "L10")
		(22 "In10.Cu" signal "L11GND")
		(24 "In11.Cu" signal "L12")
		(26 "In12.Cu" signal "L13GND")
		(2 "B.Cu" signal "BOTTOM")
		(9 "F.Adhes" user "F.Adhesive")
		(11 "B.Adhes" user "B.Adhesive")
		(13 "F.Paste" user "Package Geometry/Pastemask Top")
		(15 "B.Paste" user "Package Geometry/Pastemask Bottom")
		(5 "F.SilkS" user "Ref Des/Silkscreen Top")
		(7 "B.SilkS" user "Ref Des/Silkscreen Bottom")
		(1 "F.Mask" user "Board Geometry/Soldermask Top")
		(3 "B.Mask" user "Board Geometry/Soldermask Bottom")
		(17 "Dwgs.User" user "User.Drawings")
		(19 "Cmts.User" user "User.Comments")
		(21 "Eco1.User" user "User.Eco1")
		(23 "Eco2.User" user "User.Eco2")
		(25 "Edge.Cuts" user "Board Geometry/Outline")
		(27 "Margin" user)
		(31 "F.CrtYd" user "Package Geometry/Place Bound Top")
		(29 "B.CrtYd" user "Package Geometry/Place Bound Bottom")
		(35 "F.Fab" user "Ref Des/Assembly Top")
		(33 "B.Fab" user "Ref Des/Assembly Bottom")
	)
	(footprint ""
		(layer "B.Cu")
		(at 376.7328 -135.5598 180)
		(property "Reference" "C3M21"
			(at 0 0 0)
			(layer "B.SilkS")
			(hide yes)
			(effects
				(font
					(size 1.27 1.27)
				)
				(justify mirror)
			)
		)
		(property "Value" ""
			(at 0 0 0)
			(layer "B.Fab")
			(effects
				(font
					(size 1.27 1.27)
				)
				(justify mirror)
			)
		)
		(duplicate_pad_numbers_are_jumpers no)
		(fp_rect
			(start 0.3048 -0.1016)
			(end -0.3048 0.9906)
			(stroke
				(width 0)
				(type default)
			)
			(fill no)
			(layer "B.CrtYd")
		)
		(fp_line
			(start 0.3048 0.9906)
			(end -0.3048 0.9906)
			(stroke
				(width 0.1)
				(type default)
			)
			(layer "B.Fab")
		)
		(fp_line
			(start 0.3048 -0.1016)
			(end 0.3048 0.9906)
			(stroke
				(width 0.1)
				(type default)
			)
			(layer "B.Fab")
		)
		(fp_line
			(start -0.3048 0.9906)
			(end -0.3048 -0.1016)
			(stroke
				(width 0.1)
				(type default)
			)
			(layer "B.Fab")
		)
		(fp_line
			(start -0.3048 -0.1016)
			(end 0.3048 -0.1016)
			(stroke
				(width 0.1)
				(type default)
			)
			(layer "B.Fab")
		)
		(pad "1" smd rect
			(at 0 0)
			(size 0.508 0.508)
			(layers "B.Cu" "B.Mask" "B.Paste")
			(net "P1V05_PCH_STBY")
		)
		(pad "2" smd rect
			(at 0 0.889)
			(size 0.508 0.508)
			(layers "B.Cu" "B.Mask" "B.Paste")
			(net "GND")
		)
		(zone
			(layer "B.Cu")
			(hatch none 0.5)
			(connect_pads
				(clearance 0)
			)
			(min_thickness 0.25)
			(keepout
				(tracks allowed)
				(vias not_allowed)
				(pads allowed)
				(copperpour not_allowed)
				(footprints allowed)
			)
			(placement
				(enabled no)
				(sheetname "")
			)
			(fill
				(thermal_gap 0.5)
				(thermal_bridge_width 0.5)
				(island_removal_mode 0)
			)
			(polygon
				(pts
					(xy 376.4788 -135.8138) (xy 376.9868 -135.8138) (xy 376.9868 -136.1948) (xy 376.4788 -136.1948)
				)
			)
		)
		(zone
			(layer "B.Cu")
			(hatch none 0.5)
			(connect_pads
				(clearance 0)
			)
			(min_thickness 0.25)
			(keepout
				(tracks not_allowed)
				(vias allowed)
				(pads allowed)
				(copperpour not_allowed)
				(footprints allowed)
			)
			(placement
				(enabled no)
				(sheetname "")
			)
			(fill
				(thermal_gap 0.5)
				(thermal_bridge_width 0.5)
				(island_removal_mode 0)
			)
			(polygon
				(pts
					(xy 376.4788 -135.8138) (xy 376.9868 -135.8138) (xy 376.9868 -136.1948) (xy 376.4788 -136.1948)
				)
			)
		)
	)
	(footprint ""
		(layer "B.Cu")
		(at 106.604054 -68.17614 180)
		(property "Reference" "C8P32"
			(at 0 0 0)
			(layer "B.SilkS")
			(hide yes)
			(effects
				(font
					(size 1.27 1.27)
				)
				(justify mirror)
			)
		)
		(property "Value" ""
			(at 0 0 0)
			(layer "B.Fab")
			(effects
				(font
					(size 1.27 1.27)
				)
				(justify mirror)
			)
		)
		(duplicate_pad_numbers_are_jumpers no)
		(fp_poly
			(pts
				(xy 0.7239 -0.2159) (xy -0.7239 -0.2159) (xy -0.7239 1.9939) (xy 0.7239 1.9939)
			)
			(stroke
				(width 0)
				(type default)
			)
			(fill no)
			(layer "B.CrtYd")
		)
		(fp_line
			(start 0.7239 1.9939)
			(end -0.7239 1.9939)
			(stroke
				(width 0.1)
				(type default)
			)
			(layer "B.Fab")
		)
		(fp_line
			(start 0.7239 -0.2159)
			(end 0.7239 1.9939)
			(stroke
				(width 0.1)
				(type default)
			)
			(layer "B.Fab")
		)
		(fp_line
			(start -0.7239 1.9939)
			(end -0.7239 -0.2159)
			(stroke
				(width 0.1)
				(type default)
			)
			(layer "B.Fab")
		)
		(fp_line
			(start -0.7239 -0.2159)
			(end 0.7239 -0.2159)
			(stroke
				(width 0.1)
				(type default)
			)
			(layer "B.Fab")
		)
		(pad "1" smd rect
			(at 0 0)
			(size 1.27 1.016)
			(layers "B.Cu" "B.Mask" "B.Paste")
			(net "PVDDQ_GHJ")
		)
		(pad "2" smd rect
			(at 0 1.778)
			(size 1.27 1.016)
			(layers "B.Cu" "B.Mask" "B.Paste")
			(net "GND")
		)
		(zone
			(layer "B.Cu")
			(hatch none 0.5)
			(connect_pads
				(clearance 0)
			)
			(min_thickness 0.25)
			(keepout
				(tracks not_allowed)
				(vias allowed)
				(pads allowed)
				(copperpour not_allowed)
				(footprints allowed)
			)
			(placement
				(enabled no)
				(sheetname "")
			)
			(fill
				(thermal_gap 0.5)
				(thermal_bridge_width 0.5)
				(island_removal_mode 0)
			)
			(polygon
				(pts
					(xy 105.969054 -68.68414) (xy 107.239054 -68.68414) (xy 107.239054 -69.44614) (xy 105.969054 -69.44614)
				)
			)
		)
	)
	(footprint ""
		(layer "B.Cu")
		(at 20.3835 -90.1065 -90)
		(property "Reference" "Q6W1"
			(at 0.229362 -1.2065 270)
			(unlocked yes)
			(layer "B.SilkS")
			(effects
				(font
					(size 0.4064 0.254)
					(thickness 0.1524)
				)
				(justify left mirror)
			)
		)
		(property "Value" ""
			(at 0 0 90)
			(layer "B.Fab")
			(effects
				(font
					(size 1.27 1.27)
				)
				(justify mirror)
			)
		)
		(duplicate_pad_numbers_are_jumpers no)
		(fp_line
			(start -1.778 2.4765)
			(end -1.778 1.5875)
			(stroke
				(width 0.1524)
				(type default)
			)
			(layer "B.SilkS")
		)
		(fp_line
			(start -0.9525 2.4765)
			(end -1.778 2.4765)
			(stroke
				(width 0.1524)
				(type default)
			)
			(layer "B.SilkS")
		)
		(fp_line
			(start -0.381 0.635)
			(end -0.381 1.27)
			(stroke
				(width 0.1524)
				(type default)
			)
			(layer "B.SilkS")
		)
		(fp_line
			(start -1.778 -0.5715)
			(end -1.778 0.3175)
			(stroke
				(width 0.1524)
				(type default)
			)
			(layer "B.SilkS")
		)
		(fp_line
			(start -0.9525 -0.5715)
			(end -1.778 -0.5715)
			(stroke
				(width 0.1524)
				(type default)
			)
			(layer "B.SilkS")
		)
		(fp_circle
			(center 0.9525 -0.9271)
			(end 0.9525 -1.0541)
			(stroke
				(width 0.254)
				(type default)
			)
			(fill no)
			(layer "B.SilkS")
		)
		(fp_poly
			(pts
				(xy -1.778 2.4765) (xy -0.381 2.4765) (xy -0.381 -0.5715) (xy -1.778 -0.5715)
			)
			(stroke
				(width 0)
				(type default)
			)
			(fill no)
			(layer "B.CrtYd")
		)
		(fp_line
			(start -1.778 2.4765)
			(end -1.778 -0.5715)
			(stroke
				(width 0.1)
				(type default)
			)
			(layer "B.Fab")
		)
		(fp_line
			(start -0.381 2.4765)
			(end -1.778 2.4765)
			(stroke
				(width 0.1)
				(type default)
			)
			(layer "B.Fab")
		)
		(fp_line
			(start -1.778 -0.5715)
			(end -0.381 -0.5715)
			(stroke
				(width 0.1)
				(type default)
			)
			(layer "B.Fab")
		)
		(fp_line
			(start -0.381 -0.5715)
			(end -0.381 2.4765)
			(stroke
				(width 0.1)
				(type default)
			)
			(layer "B.Fab")
		)
		(fp_circle
			(center 0.9525 -0.9271)
			(end 0.9525 -1.0541)
			(stroke
				(width 0.254)
				(type default)
			)
			(fill no)
			(layer "B.Fab")
		)
		(pad "1" smd rect
			(at 0 0 90)
			(size 1.143 0.508)
			(layers "B.Cu" "B.Mask" "B.Paste")
			(net "UV_HIGH_SET")
		)
		(pad "2" smd rect
			(at 0 1.905 90)
			(size 1.143 0.508)
			(layers "B.Cu" "B.Mask" "B.Paste")
			(net "GND")
		)
		(pad "3" smd rect
			(at -2.159 0.9525 90)
			(size 1.143 0.508)
			(layers "B.Cu" "B.Mask" "B.Paste")
			(net "UV_HIGH_SET_N")
		)
	)
	(footprint ""
		(layer "B.Cu")
		(at 272.861532 -17.7546 90)
		(property "Reference" "C5T6"
			(at -1.848866 0.752348 90)
			(unlocked yes)
			(layer "B.SilkS")
			(effects
				(font
					(size 1.27 0.9652)
					(thickness 0.1524)
				)
				(justify mirror)
			)
		)
		(property "Value" ""
			(at 0 0 90)
			(layer "B.Fab")
			(effects
				(font
					(size 1.27 1.27)
				)
				(justify mirror)
			)
		)
		(duplicate_pad_numbers_are_jumpers no)
		(fp_rect
			(start 0.500126 1.598422)
			(end -0.500126 -0.201422)
			(stroke
				(width 0)
				(type default)
			)
			(fill no)
			(layer "B.CrtYd")
		)
		(fp_line
			(start 0.500126 -0.201422)
			(end -0.500126 -0.201422)
			(stroke
				(width 0.1)
				(type default)
			)
			(layer "B.Fab")
		)
		(fp_line
			(start -0.500126 -0.201422)
			(end -0.500126 1.598422)
			(stroke
				(width 0.1)
				(type default)
			)
			(layer "B.Fab")
		)
		(fp_line
			(start 0.500126 1.598422)
			(end 0.500126 -0.201422)
			(stroke
				(width 0.1)
				(type default)
			)
			(layer "B.Fab")
		)
		(fp_line
			(start -0.500126 1.598422)
			(end 0.500126 1.598422)
			(stroke
				(width 0.1)
				(type default)
			)
			(layer "B.Fab")
		)
		(pad "1" smd rect
			(at 0 0)
			(size 0.889 0.9906)
			(layers "B.Cu" "B.Mask" "B.Paste")
			(net "PVDDQ_ABC")
		)
		(pad "2" smd rect
			(at 0 1.397)
			(size 0.889 0.9906)
			(layers "B.Cu" "B.Mask" "B.Paste")
			(net "GND")
		)
		(zone
			(layer "B.Cu")
			(hatch none 0.5)
			(connect_pads
				(clearance 0)
			)
			(min_thickness 0.25)
			(keepout
				(tracks not_allowed)
				(vias allowed)
				(pads allowed)
				(copperpour not_allowed)
				(footprints allowed)
			)
			(placement
				(enabled no)
				(sheetname "")
			)
			(fill
				(thermal_gap 0.5)
				(thermal_bridge_width 0.5)
				(island_removal_mode 0)
			)
			(polygon
				(pts
					(xy 273.814032 -18.2499) (xy 273.306032 -18.2499) (xy 273.306032 -17.2593) (xy 273.814032 -17.2593)
				)
			)
		)
		(zone
			(layer "B.Cu")
			(hatch none 0.5)
			(connect_pads
				(clearance 0)
			)
			(min_thickness 0.25)
			(keepout
				(tracks allowed)
				(vias not_allowed)
				(pads allowed)
				(copperpour not_allowed)
				(footprints allowed)
			)
			(placement
				(enabled no)
				(sheetname "")
			)
			(fill
				(thermal_gap 0.5)
				(thermal_bridge_width 0.5)
				(island_removal_mode 0)
			)
			(polygon
				(pts
					(xy 273.814032 -18.2499) (xy 273.306032 -18.2499) (xy 273.306032 -17.2593) (xy 273.814032 -17.2593)
				)
			)
		)
	)
	(footprint ""
		(layer "B.Cu")
		(at 361.444794 -43.194986 -90)
		(property "Reference" "R2T33"
			(at 0 0 90)
			(layer "B.SilkS")
			(hide yes)
			(effects
				(font
					(size 1.27 1.27)
				)
				(justify mirror)
			)
		)
		(property "Value" ""
			(at 0 0 90)
			(layer "B.Fab")
			(effects
				(font
					(size 1.27 1.27)
				)
				(justify mirror)
			)
		)
		(duplicate_pad_numbers_are_jumpers no)
		(fp_poly
			(pts
				(xy 0.2794 -0.1016) (xy -0.2794 -0.1016) (xy -0.2794 0.9906) (xy 0.2794 0.9906)
			)
			(stroke
				(width 0)
				(type default)
			)
			(fill no)
			(layer "B.CrtYd")
		)
		(fp_line
			(start -0.2794 0.9906)
			(end -0.2794 -0.1016)
			(stroke
				(width 0.1)
				(type default)
			)
			(layer "B.Fab")
		)
		(fp_line
			(start 0.2794 0.9906)
			(end -0.2794 0.9906)
			(stroke
				(width 0.1)
				(type default)
			)
			(layer "B.Fab")
		)
		(fp_line
			(start -0.2794 -0.1016)
			(end 0.2794 -0.1016)
			(stroke
				(width 0.1)
				(type default)
			)
			(layer "B.Fab")
		)
		(fp_line
			(start 0.2794 -0.1016)
			(end 0.2794 0.9906)
			(stroke
				(width 0.1)
				(type default)
			)
			(layer "B.Fab")
		)
		(pad "1" smd rect
			(at 0 0 90)
			(size 0.508 0.508)
			(layers "B.Cu" "B.Mask" "B.Paste")
			(net "FM_CPU_ERR1_LVT3_K_N")
		)
		(pad "2" smd rect
			(at 0 0.889 90)
			(size 0.508 0.508)
			(layers "B.Cu" "B.Mask" "B.Paste")
			(net "FM_CPU_ERR1_LVT3_N")
		)
		(zone
			(layer "B.Cu")
			(hatch none 0.5)
			(connect_pads
				(clearance 0)
			)
			(min_thickness 0.25)
			(keepout
				(tracks not_allowed)
				(vias allowed)
				(pads allowed)
				(copperpour not_allowed)
				(footprints allowed)
			)
			(placement
				(enabled no)
				(sheetname "")
			)
			(fill
				(thermal_gap 0.5)
				(thermal_bridge_width 0.5)
				(island_removal_mode 0)
			)
			(polygon
				(pts
					(xy 360.809794 -42.940986) (xy 360.809794 -43.448986) (xy 361.190794 -43.448986) (xy 361.190794 -42.940986)
				)
			)
		)
		(zone
			(layer "B.Cu")
			(hatch none 0.5)
			(connect_pads
				(clearance 0)
			)
			(min_thickness 0.25)
			(keepout
				(tracks allowed)
				(vias not_allowed)
				(pads allowed)
				(copperpour not_allowed)
				(footprints allowed)
			)
			(placement
				(enabled no)
				(sheetname "")
			)
			(fill
				(thermal_gap 0.5)
				(thermal_bridge_width 0.5)
				(island_removal_mode 0)
			)
			(polygon
				(pts
					(xy 361.190794 -42.940986) (xy 361.190794 -43.448986) (xy 360.809794 -43.448986) (xy 360.809794 -42.940986)
				)
			)
		)
	)
	(footprint ""
		(layer "B.Cu")
		(at 33.5407 -69.4182 90)
		(property "Reference" "C1D15"
			(at 0 0 90)
			(layer "B.SilkS")
			(hide yes)
			(effects
				(font
					(size 1.27 1.27)
				)
				(justify mirror)
			)
		)
		(property "Value" "*"
			(at -1.1811 -2.8194 90)
			(unlocked yes)
			(layer "B.Fab")
			(hide yes)
			(effects
				(font
					(size 1.27 1.016)
					(thickness 0.1524)
				)
				(justify mirror)
			)
		)
		(property "Device Type" "SC1U10V2KX-4-GP_SMD-BCG6-SC1U1A"
			(at -1.1811 -4.3434 90)
			(unlocked yes)
			(layer "B.Fab")
			(hide yes)
			(effects
				(font
					(size 1.27 1.016)
					(thickness 0.1524)
				)
				(justify mirror)
			)
		)
		(duplicate_pad_numbers_are_jumpers no)
		(fp_rect
			(start 0.4318 0.9525)
			(end -0.4318 -0.9525)
			(stroke
				(width 0)
				(type default)
			)
			(fill no)
			(layer "B.CrtYd")
		)
		(fp_rect
			(start 0.4318 0.9525)
			(end -0.4318 -0.9525)
			(stroke
				(width 0)
				(type default)
			)
			(fill no)
			(layer "B.Fab")
		)
		(pad "1" smd custom
			(at 0 -0.4445 270)
			(size 0.1524 0.1524)
			(layers "B.Cu" "B.Mask" "B.Paste")
			(net "P5V_STBY")
			(options
				(clearance outline)
				(anchor circle)
			)
			(primitives
				(gr_poly
					(pts
						(arc
							(start 0.3048 0.2032)
							(mid 0.275042 0.275042)
							(end 0.2032 0.3048)
						)
						(arc
							(start -0.2032 0.3048)
							(mid -0.275042 0.275042)
							(end -0.3048 0.2032)
						)
						(arc
							(start -0.3048 -0.2032)
							(mid -0.275042 -0.275042)
							(end -0.2032 -0.3048)
						)
						(arc
							(start 0.2032 -0.3048)
							(mid 0.275042 -0.275042)
							(end 0.3048 -0.2032)
						)
					)
					(width 0)
					(fill yes)
				)
			)
		)
		(pad "2" smd custom
			(at 0 0.4445 270)
			(size 0.1524 0.1524)
			(layers "B.Cu" "B.Mask" "B.Paste")
			(net "GND")
			(options
				(clearance outline)
				(anchor circle)
			)
			(primitives
				(gr_poly
					(pts
						(arc
							(start 0.3048 0.2032)
							(mid 0.275042 0.275042)
							(end 0.2032 0.3048)
						)
						(arc
							(start -0.2032 0.3048)
							(mid -0.275042 0.275042)
							(end -0.3048 0.2032)
						)
						(arc
							(start -0.3048 -0.2032)
							(mid -0.275042 -0.275042)
							(end -0.2032 -0.3048)
						)
						(arc
							(start 0.2032 -0.3048)
							(mid 0.275042 -0.275042)
							(end 0.3048 -0.2032)
						)
					)
					(width 0)
					(fill yes)
				)
			)
		)
	)
	(footprint ""
		(layer "B.Cu")
		(at 431.2412 -22.5298 180)
		(property "Reference" "R1U24"
			(at 0 0 0)
			(layer "B.SilkS")
			(hide yes)
			(effects
				(font
					(size 1.27 1.27)
				)
				(justify mirror)
			)
		)
		(property "Value" ""
			(at 0 0 0)
			(layer "B.Fab")
			(effects
				(font
					(size 1.27 1.27)
				)
				(justify mirror)
			)
		)
		(duplicate_pad_numbers_are_jumpers no)
		(fp_poly
			(pts
				(xy 0.2794 -0.1016) (xy -0.2794 -0.1016) (xy -0.2794 0.9906) (xy 0.2794 0.9906)
			)
			(stroke
				(width 0)
				(type default)
			)
			(fill no)
			(layer "B.CrtYd")
		)
		(fp_line
			(start 0.2794 0.9906)
			(end -0.2794 0.9906)
			(stroke
				(width 0.1)
				(type default)
			)
			(layer "B.Fab")
		)
		(fp_line
			(start 0.2794 -0.1016)
			(end 0.2794 0.9906)
			(stroke
				(width 0.1)
				(type default)
			)
			(layer "B.Fab")
		)
		(fp_line
			(start -0.2794 0.9906)
			(end -0.2794 -0.1016)
			(stroke
				(width 0.1)
				(type default)
			)
			(layer "B.Fab")
		)
		(fp_line
			(start -0.2794 -0.1016)
			(end 0.2794 -0.1016)
			(stroke
				(width 0.1)
				(type default)
			)
			(layer "B.Fab")
		)
		(pad "1" smd rect
			(at 0 0)
			(size 0.508 0.508)
			(layers "B.Cu" "B.Mask" "B.Paste")
			(net "P3V3_STBY")
		)
		(pad "2" smd rect
			(at 0 0.889)
			(size 0.508 0.508)
			(layers "B.Cu" "B.Mask" "B.Paste")
			(net "FM_BOARD_SKU_ID2")
		)
		(zone
			(layer "B.Cu")
			(hatch none 0.5)
			(connect_pads
				(clearance 0)
			)
			(min_thickness 0.25)
			(keepout
				(tracks not_allowed)
				(vias allowed)
				(pads allowed)
				(copperpour not_allowed)
				(footprints allowed)
			)
			(placement
				(enabled no)
				(sheetname "")
			)
			(fill
				(thermal_gap 0.5)
				(thermal_bridge_width 0.5)
				(island_removal_mode 0)
			)
			(polygon
				(pts
					(xy 430.9872 -23.1648) (xy 431.4952 -23.1648) (xy 431.4952 -22.7838) (xy 430.9872 -22.7838)
				)
			)
		)
		(zone
			(layer "B.Cu")
			(hatch none 0.5)
			(connect_pads
				(clearance 0)
			)
			(min_thickness 0.25)
			(keepout
				(tracks allowed)
				(vias not_allowed)
				(pads allowed)
				(copperpour not_allowed)
				(footprints allowed)
			)
			(placement
				(enabled no)
				(sheetname "")
			)
			(fill
				(thermal_gap 0.5)
				(thermal_bridge_width 0.5)
				(island_removal_mode 0)
			)
			(polygon
				(pts
					(xy 430.9872 -22.7838) (xy 431.4952 -22.7838) (xy 431.4952 -23.1648) (xy 430.9872 -23.1648)
				)
			)
		)
	)
)
